(kicad_pcb
	(version 20241229)
	(generator "pcbnew")
	(generator_version "9.0")
	(general
		(thickness 1.62)
		(legacy_teardrops no)
	)
	(paper "A3")
	(title_block
		(title "COM Express 7 Baseboard")
		(date "2025-02-04")
		(rev "1.1.2")
		(company "Antmicro Ltd")
		(comment 1 "www.antmicro.com")
		(comment 9 "footprints 402-406 of 802")
	)
	(layers
		(0 "F.Cu" signal)
		(4 "In1.Cu" signal)
		(6 "In2.Cu" signal)
		(8 "In3.Cu" signal)
		(10 "In4.Cu" signal)
		(12 "In5.Cu" signal)
		(14 "In6.Cu" signal)
		(2 "B.Cu" signal)
		(9 "F.Adhes" user "F.Adhesive")
		(11 "B.Adhes" user "B.Adhesive")
		(13 "F.Paste" user)
		(15 "B.Paste" user)
		(5 "F.SilkS" user "F.Silkscreen")
		(7 "B.SilkS" user "B.Silkscreen")
		(1 "F.Mask" user)
		(3 "B.Mask" user)
		(17 "Dwgs.User" user "User.Drawings")
		(19 "Cmts.User" user "User.Comments")
		(21 "Eco1.User" user "User.Eco1")
		(23 "Eco2.User" user "User.Eco2")
		(25 "Edge.Cuts" user)
		(27 "Margin" user)
		(31 "F.CrtYd" user "F.Courtyard")
		(29 "B.CrtYd" user "B.Courtyard")
		(35 "F.Fab" user)
		(33 "B.Fab" user)
	)
	(footprint "antmicro-footprints:R_0402_1005Metric"
		(layer "F.Cu")
		(at 114.4 144.36 90)
		(descr "Resistor SMD 0402")
		(tags "resistor SMD 0402")
		(property "Reference" "R212"
			(at 0.8 0.4 90)
			(layer "F.SilkS")
			(effects
				(font
					(size 0.7 0.7)
					(thickness 0.15)
				)
				(justify left bottom)
			)
		)
		(property "Value" "R_1k_0402"
			(at -1.011843 1.772047 90)
			(layer "F.Fab")
			(effects
				(font
					(size 0.7 0.7)
					(thickness 0.15)
				)
				(justify left bottom)
			)
		)
		(property "Datasheet" "https://www.bourns.com/docs/product-datasheets/cr.pdf"
			(at 0 0 90)
			(layer "F.Fab")
			(hide yes)
			(effects
				(font
					(size 1.27 1.27)
					(thickness 0.15)
				)
			)
		)
		(property "Author" "Antmicro"
			(at 258.76 29.96 0)
			(layer "F.Fab")
			(hide yes)
			(effects
				(font
					(size 1 1)
					(thickness 0.15)
				)
			)
		)
		(property "License" "Apache-2.0"
			(at 258.76 29.96 0)
			(layer "F.Fab")
			(hide yes)
			(effects
				(font
					(size 1 1)
					(thickness 0.15)
				)
			)
		)
		(property "MPN" "CR0402-FX-1001GLF"
			(at 258.76 29.96 0)
			(layer "F.Fab")
			(hide yes)
			(effects
				(font
					(size 1 1)
					(thickness 0.15)
				)
			)
		)
		(property "Manufacturer" "Bourns"
			(at 258.76 29.96 0)
			(layer "F.Fab")
			(hide yes)
			(effects
				(font
					(size 1 1)
					(thickness 0.15)
				)
			)
		)
		(property "Public" "False"
			(at 258.76 29.96 0)
			(layer "F.Fab")
			(hide yes)
			(effects
				(font
					(size 1 1)
					(thickness 0.15)
				)
			)
		)
		(property "Tolerance" "1%"
			(at 258.76 29.96 0)
			(layer "F.Fab")
			(hide yes)
			(effects
				(font
					(size 1 1)
					(thickness 0.15)
				)
			)
		)
		(property "Val" "1k"
			(at 258.76 29.96 0)
			(layer "F.Fab")
			(hide yes)
			(effects
				(font
					(size 1 1)
					(thickness 0.15)
				)
			)
		)
		(sheetname "PCIe redriver")
		(sheetfile "pcie_redriver.kicad_sch")
		(attr smd)
		(fp_rect
			(start -0.925 -0.47)
			(end 0.925 0.47)
			(stroke
				(width 0.05)
				(type default)
			)
			(fill no)
			(layer "F.CrtYd")
		)
		(fp_rect
			(start -0.5 -0.25)
			(end 0.5 0.25)
			(stroke
				(width 0.15)
				(type solid)
			)
			(fill no)
			(layer "F.Fab")
		)
		(pad "1" smd roundrect
			(at -0.48 0 90)
			(size 0.59 0.64)
			(layers "F.Cu" "F.Mask" "F.Paste")
			(roundrect_rratio 0.25)
			(net 2 "+3V3")
			(pintype "passive")
			(teardrops
				(best_length_ratio 0.2)
				(max_length 1)
				(best_width_ratio 0.9)
				(max_width 2)
				(curved_edges yes)
				(filter_ratio 0.9)
				(enabled yes)
				(allow_two_segments yes)
				(prefer_zone_connections yes)
			)
		)
		(pad "2" smd roundrect
			(at 0.48 0 90)
			(size 0.59 0.64)
			(layers "F.Cu" "F.Mask" "F.Paste")
			(roundrect_rratio 0.25)
			(net 628 "/PCIe redriver/TX_SW")
			(pintype "passive")
			(teardrops
				(best_length_ratio 0.2)
				(max_length 1)
				(best_width_ratio 0.9)
				(max_width 2)
				(curved_edges yes)
				(filter_ratio 0.9)
				(enabled yes)
				(allow_two_segments yes)
				(prefer_zone_connections yes)
			)
		)
	)
	(footprint "antmicro-footprints:R_0402_1005Metric"
		(layer "F.Cu")
		(at 191.469122 140.186326 -135)
		(descr "Resistor SMD 0402")
		(tags "resistor SMD 0402")
		(property "Reference" "R229"
			(at 1.069206 -0.415818 45)
			(layer "F.SilkS")
			(effects
				(font
					(size 0.7 0.7)
					(thickness 0.15)
				)
				(justify right bottom)
			)
		)
		(property "Value" "R_1k_0402"
			(at -1.011843 1.772046 45)
			(layer "F.Fab")
			(effects
				(font
					(size 0.7 0.7)
					(thickness 0.15)
				)
				(justify right bottom)
			)
		)
		(property "Datasheet" "https://www.bourns.com/docs/product-datasheets/cr.pdf"
			(at 0 0 45)
			(layer "B.Fab")
			(hide yes)
			(effects
				(font
					(size 1.27 1.27)
					(thickness 0.15)
				)
				(justify mirror)
			)
		)
		(property "Author" "Antmicro"
			(at 0 0 45)
			(layer "F.Fab")
			(hide yes)
			(effects
				(font
					(size 1 1)
					(thickness 0.15)
				)
			)
		)
		(property "License" "Apache-2.0"
			(at 0 0 45)
			(layer "F.Fab")
			(hide yes)
			(effects
				(font
					(size 1 1)
					(thickness 0.15)
				)
			)
		)
		(property "MPN" "CR0402-FX-1001GLF"
			(at 0 0 45)
			(layer "F.Fab")
			(hide yes)
			(effects
				(font
					(size 1 1)
					(thickness 0.15)
				)
			)
		)
		(property "Manufacturer" "Bourns"
			(at 0 0 45)
			(layer "F.Fab")
			(hide yes)
			(effects
				(font
					(size 1 1)
					(thickness 0.15)
				)
			)
		)
		(property "Public" "False"
			(at 0 0 45)
			(layer "F.Fab")
			(hide yes)
			(effects
				(font
					(size 1 1)
					(thickness 0.15)
				)
			)
		)
		(property "Tolerance" "1%"
			(at 0 0 45)
			(layer "F.Fab")
			(hide yes)
			(effects
				(font
					(size 1 1)
					(thickness 0.15)
				)
			)
		)
		(property "Val" "1k"
			(at 0 0 45)
			(layer "F.Fab")
			(hide yes)
			(effects
				(font
					(size 1 1)
					(thickness 0.15)
				)
			)
		)
		(sheetname "PCIe redriver")
		(sheetfile "pcie_redriver.kicad_sch")
		(attr smd)
		(fp_poly
			(pts
				(xy -0.925 -0.47) (xy 0.925 -0.47) (xy 0.925 0.47) (xy -0.925 0.47)
			)
			(stroke
				(width 0.05)
				(type default)
			)
			(fill no)
			(layer "F.CrtYd")
		)
		(fp_poly
			(pts
				(xy -0.5 -0.25) (xy 0.5 -0.25) (xy 0.5 0.25) (xy -0.5 0.25)
			)
			(stroke
				(width 0.15)
				(type solid)
			)
			(fill no)
			(layer "F.Fab")
		)
		(pad "1" smd roundrect
			(at -0.48 0 225)
			(size 0.59 0.64)
			(layers "F.Cu" "F.Mask" "F.Paste")
			(roundrect_rratio 0.25)
			(net 2 "+3V3")
			(pintype "passive")
			(teardrops
				(best_length_ratio 0.2)
				(max_length 1)
				(best_width_ratio 0.9)
				(max_width 2)
				(curved_edges yes)
				(filter_ratio 0.9)
				(enabled yes)
				(allow_two_segments yes)
				(prefer_zone_connections yes)
			)
		)
		(pad "2" smd roundrect
			(at 0.48 0 225)
			(size 0.59 0.64)
			(layers "F.Cu" "F.Mask" "F.Paste")
			(roundrect_rratio 0.25)
			(net 978 "/PCIe redriver/RX_EQ0")
			(pintype "passive")
			(teardrops
				(best_length_ratio 0.2)
				(max_length 1)
				(best_width_ratio 0.9)
				(max_width 2)
				(curved_edges yes)
				(filter_ratio 0.9)
				(enabled yes)
				(allow_two_segments yes)
				(prefer_zone_connections yes)
			)
		)
	)
	(footprint "antmicro-footprints:TP_SMD_0.75mm"
		(layer "F.Cu")
		(at 153.1 128.71)
		(property "Reference" "TP59"
			(at 0.4 -3.3 90)
			(layer "F.SilkS")
			(effects
				(font
					(size 0.7 0.7)
					(thickness 0.15)
				)
				(justify left bottom)
			)
		)
		(property "Value" "TP_0.75mm_SMD"
			(at 0 1.2 0)
			(layer "F.Fab")
			(effects
				(font
					(size 0.7 0.7)
					(thickness 0.15)
				)
				(justify left bottom)
			)
		)
		(property "Author" "Antmicro"
			(at 0 0 0)
			(layer "F.Fab")
			(hide yes)
			(effects
				(font
					(size 1 1)
					(thickness 0.15)
				)
			)
		)
		(property "License" "Apache-2.0"
			(at 0 0 0)
			(layer "F.Fab")
			(hide yes)
			(effects
				(font
					(size 1 1)
					(thickness 0.15)
				)
			)
		)
		(property "MPN" ""
			(at 0 0 0)
			(layer "F.Fab")
			(hide yes)
			(effects
				(font
					(size 1 1)
					(thickness 0.15)
				)
			)
		)
		(property "Manufacturer" ""
			(at 0 0 0)
			(layer "F.Fab")
			(hide yes)
			(effects
				(font
					(size 1 1)
					(thickness 0.15)
				)
			)
		)
		(property "Public" "False"
			(at 0 0 0)
			(layer "F.Fab")
			(hide yes)
			(effects
				(font
					(size 1 1)
					(thickness 0.15)
				)
			)
		)
		(sheetname "KR to SFI #1")
		(sheetfile "kr_sfi.kicad_sch")
		(attr exclude_from_pos_files exclude_from_bom)
		(fp_circle
			(center 0 0)
			(end 0.475 0)
			(stroke
				(width 0.05)
				(type default)
			)
			(fill no)
			(layer "F.CrtYd")
		)
		(pad "1" smd circle
			(at 0 0)
			(size 0.75 0.75)
			(layers "F.Cu" "F.Mask")
			(net 722 "/2xSFP+/KR to SFI #1/TDI")
			(pinfunction "1")
			(pintype "passive")
			(teardrops
				(best_length_ratio 0.4)
				(max_length 1)
				(best_width_ratio 0.9)
				(max_width 2)
				(curved_edges yes)
				(filter_ratio 0.9)
				(enabled yes)
				(allow_two_segments yes)
				(prefer_zone_connections yes)
			)
		)
	)
	(footprint "antmicro-footprints:SOT-23-3"
		(layer "F.Cu")
		(at 202.45 80.75 90)
		(property "Reference" "Q13"
			(at -1.2 2.65 90)
			(layer "F.SilkS")
			(effects
				(font
					(size 0.7 0.7)
					(thickness 0.15)
				)
				(justify left bottom)
			)
		)
		(property "Value" "MMBT3904LT1G"
			(at -1.9 2.7 90)
			(layer "F.Fab")
			(effects
				(font
					(size 0.7 0.7)
					(thickness 0.15)
				)
				(justify left bottom)
			)
		)
		(property "Datasheet" "https://eu.mouser.com/datasheet/2/308/1/MMBT3904LT1_D-2316262.pdf"
			(at 0 0 90)
			(layer "F.Fab")
			(hide yes)
			(effects
				(font
					(size 1.27 1.27)
					(thickness 0.15)
				)
			)
		)
		(property "Author" "Antmicro"
			(at 279.335773 -117.971447 0)
			(layer "F.Fab")
			(hide yes)
			(effects
				(font
					(size 1 1)
					(thickness 0.15)
				)
			)
		)
		(property "License" "Apache-2.0"
			(at 279.335773 -117.971447 0)
			(layer "F.Fab")
			(hide yes)
			(effects
				(font
					(size 1 1)
					(thickness 0.15)
				)
			)
		)
		(property "MPN" "MMBT3904LT1G"
			(at 279.335773 -117.971447 0)
			(layer "F.Fab")
			(hide yes)
			(effects
				(font
					(size 1 1)
					(thickness 0.15)
				)
			)
		)
		(property "Manufacturer" "Onsemi"
			(at 279.335773 -117.971447 0)
			(layer "F.Fab")
			(hide yes)
			(effects
				(font
					(size 1 1)
					(thickness 0.15)
				)
			)
		)
		(property "Public" "False"
			(at 279.335773 -117.971447 0)
			(layer "F.Fab")
			(hide yes)
			(effects
				(font
					(size 1 1)
					(thickness 0.15)
				)
			)
		)
		(property ki_fp_filters "SOT?323*")
		(sheetname "Power")
		(sheetfile "power.kicad_sch")
		(attr smd)
		(fp_line
			(start 0.7 -1.5)
			(end -0.7 -1.5)
			(stroke
				(width 0.15)
				(type solid)
			)
			(layer "F.SilkS")
		)
		(fp_line
			(start -0.85 -1.35)
			(end -0.7 -1.5)
			(stroke
				(width 0.15)
				(type solid)
			)
			(layer "F.SilkS")
		)
		(fp_line
			(start -1.45 -1.35)
			(end -0.85 -1.35)
			(stroke
				(width 0.15)
				(type solid)
			)
			(layer "F.SilkS")
		)
		(fp_line
			(start 0.7 -0.4)
			(end 0.7 -1.5)
			(stroke
				(width 0.15)
				(type solid)
			)
			(layer "F.SilkS")
		)
		(fp_line
			(start 0.7 0.4)
			(end 0.7 1.5)
			(stroke
				(width 0.15)
				(type solid)
			)
			(layer "F.SilkS")
		)
		(fp_line
			(start 0.7 1.5)
			(end -0.7 1.5)
			(stroke
				(width 0.15)
				(type solid)
			)
			(layer "F.SilkS")
		)
		(fp_line
			(start -0.7 1.5)
			(end -0.7 1.35)
			(stroke
				(width 0.15)
				(type solid)
			)
			(layer "F.SilkS")
		)
		(fp_line
			(start 0.825 -1.6)
			(end 0.825 -0.45)
			(stroke
				(width 0.05)
				(type solid)
			)
			(layer "F.CrtYd")
		)
		(fp_line
			(start -0.9 -1.6)
			(end 0.825 -1.6)
			(stroke
				(width 0.05)
				(type solid)
			)
			(layer "F.CrtYd")
		)
		(fp_line
			(start -0.9 -1.6)
			(end -0.9 -1.4)
			(stroke
				(width 0.05)
				(type solid)
			)
			(layer "F.CrtYd")
		)
		(fp_line
			(start -0.9 -1.4)
			(end -1.75 -1.4)
			(stroke
				(width 0.05)
				(type solid)
			)
			(layer "F.CrtYd")
		)
		(fp_line
			(start -0.85 -0.5)
			(end -1.75 -0.5)
			(stroke
				(width 0.05)
				(type solid)
			)
			(layer "F.CrtYd")
		)
		(fp_line
			(start -1.75 -0.5)
			(end -1.75 -1.4)
			(stroke
				(width 0.05)
				(type solid)
			)
			(layer "F.CrtYd")
		)
		(fp_line
			(start 1.75 -0.45)
			(end 1.75 0.45)
			(stroke
				(width 0.05)
				(type solid)
			)
			(layer "F.CrtYd")
		)
		(fp_line
			(start 0.825 -0.45)
			(end 1.75 -0.45)
			(stroke
				(width 0.05)
				(type solid)
			)
			(layer "F.CrtYd")
		)
		(fp_line
			(start 1.75 0.45)
			(end 0.85 0.45)
			(stroke
				(width 0.05)
				(type solid)
			)
			(layer "F.CrtYd")
		)
		(fp_line
			(start 0.85 0.45)
			(end 0.85 1.65)
			(stroke
				(width 0.05)
				(type solid)
			)
			(layer "F.CrtYd")
		)
		(fp_line
			(start -0.85 0.5)
			(end -0.85 -0.5)
			(stroke
				(width 0.05)
				(type solid)
			)
			(layer "F.CrtYd")
		)
		(fp_line
			(start -1.75 0.5)
			(end -0.85 0.5)
			(stroke
				(width 0.05)
				(type solid)
			)
			(layer "F.CrtYd")
		)
		(fp_line
			(start -0.85 1.4)
			(end -1.75 1.4)
			(stroke
				(width 0.05)
				(type solid)
			)
			(layer "F.CrtYd")
		)
		(fp_line
			(start -1.75 1.4)
			(end -1.75 0.5)
			(stroke
				(width 0.05)
				(type solid)
			)
			(layer "F.CrtYd")
		)
		(fp_line
			(start 0.85 1.65)
			(end -0.85 1.65)
			(stroke
				(width 0.05)
				(type solid)
			)
			(layer "F.CrtYd")
		)
		(fp_line
			(start -0.85 1.65)
			(end -0.85 1.4)
			(stroke
				(width 0.05)
				(type solid)
			)
			(layer "F.CrtYd")
		)
		(fp_line
			(start -0.437 -1.526)
			(end 0.688 -1.526)
			(stroke
				(width 0.15)
				(type solid)
			)
			(layer "F.Fab")
		)
		(fp_line
			(start -0.437 -1.526)
			(end -0.712 -1.325)
			(stroke
				(width 0.15)
				(type solid)
			)
			(layer "F.Fab")
		)
		(fp_line
			(start -0.712 -1.325)
			(end -0.712 1.523)
			(stroke
				(width 0.15)
				(type solid)
			)
			(layer "F.Fab")
		)
		(fp_line
			(start 0.688 1.519)
			(end 0.688 -1.52)
			(stroke
				(width 0.15)
				(type solid)
			)
			(layer "F.Fab")
		)
		(fp_line
			(start -0.712 1.519)
			(end 0.688 1.519)
			(stroke
				(width 0.15)
				(type solid)
			)
			(layer "F.Fab")
		)
		(pad "1" smd roundrect
			(at -1.1 -0.951 90)
			(size 1 0.6)
			(layers "F.Cu" "F.Mask" "F.Paste")
			(roundrect_rratio 0.15)
			(net 987 "Net-(Q13-B)")
			(pinfunction "B")
			(pintype "input")
			(teardrops
				(best_length_ratio 0.2)
				(max_length 1)
				(best_width_ratio 0.9)
				(max_width 2)
				(curved_edges yes)
				(filter_ratio 0.9)
				(enabled yes)
				(allow_two_segments yes)
				(prefer_zone_connections yes)
			)
		)
		(pad "2" smd roundrect
			(at -1.1 0.949 90)
			(size 1 0.6)
			(layers "F.Cu" "F.Mask" "F.Paste")
			(roundrect_rratio 0.15)
			(net 1 "GND")
			(pinfunction "E")
			(pintype "passive")
			(teardrops
				(best_length_ratio 0.2)
				(max_length 1)
				(best_width_ratio 0.9)
				(max_width 2)
				(curved_edges yes)
				(filter_ratio 0.9)
				(enabled yes)
				(allow_two_segments yes)
				(prefer_zone_connections yes)
			)
		)
		(pad "3" smd roundrect
			(at 1.1 -0.0005 90)
			(size 1 0.6)
			(layers "F.Cu" "F.Mask" "F.Paste")
			(roundrect_rratio 0.15)
			(net 988 "Net-(Q13-C)")
			(pinfunction "C")
			(pintype "passive")
			(teardrops
				(best_length_ratio 0.2)
				(max_length 1)
				(best_width_ratio 0.9)
				(max_width 2)
				(curved_edges yes)
				(filter_ratio 0.9)
				(enabled yes)
				(allow_two_segments yes)
				(prefer_zone_connections yes)
			)
		)
	)
	(footprint "antmicro-footprints:TP_SMD_0.75mm"
		(layer "F.Cu")
		(at 145.3 128.71)
		(property "Reference" "TP57"
			(at 0.4 -3.3 90)
			(layer "F.SilkS")
			(effects
				(font
					(size 0.7 0.7)
					(thickness 0.15)
				)
				(justify left bottom)
			)
		)
		(property "Value" "TP_0.75mm_SMD"
			(at 0 1.2 0)
			(layer "F.Fab")
			(effects
				(font
					(size 0.7 0.7)
					(thickness 0.15)
				)
				(justify left bottom)
			)
		)
		(property "Author" "Antmicro"
			(at 0 0 0)
			(layer "F.Fab")
			(hide yes)
			(effects
				(font
					(size 1 1)
					(thickness 0.15)
				)
			)
		)
		(property "License" "Apache-2.0"
			(at 0 0 0)
			(layer "F.Fab")
			(hide yes)
			(effects
				(font
					(size 1 1)
					(thickness 0.15)
				)
			)
		)
		(property "MPN" ""
			(at 0 0 0)
			(layer "F.Fab")
			(hide yes)
			(effects
				(font
					(size 1 1)
					(thickness 0.15)
				)
			)
		)
		(property "Manufacturer" ""
			(at 0 0 0)
			(layer "F.Fab")
			(hide yes)
			(effects
				(font
					(size 1 1)
					(thickness 0.15)
				)
			)
		)
		(property "Public" "False"
			(at 0 0 0)
			(layer "F.Fab")
			(hide yes)
			(effects
				(font
					(size 1 1)
					(thickness 0.15)
				)
			)
		)
		(sheetname "KR to SFI #1")
		(sheetfile "kr_sfi.kicad_sch")
		(attr exclude_from_pos_files exclude_from_bom)
		(fp_circle
			(center 0 0)
			(end 0.475 0)
			(stroke
				(width 0.05)
				(type default)
			)
			(fill no)
			(layer "F.CrtYd")
		)
		(pad "1" smd circle
			(at 0 0)
			(size 0.75 0.75)
			(layers "F.Cu" "F.Mask")
			(net 720 "Net-(U43C-REFCLK1+)")
			(pinfunction "1")
			(pintype "passive")
			(teardrops
				(best_length_ratio 0.4)
				(max_length 1)
				(best_width_ratio 0.9)
				(max_width 2)
				(curved_edges yes)
				(filter_ratio 0.9)
				(enabled yes)
				(allow_two_segments yes)
				(prefer_zone_connections yes)
			)
		)
	)
)
